# BARRELEYE-G2-EXPANDER-EVT-HW-EBOM-X00-20161124-add_2nd_source_X06-20161207-Final.xls — DEPOP_GA (bom)
| FOXCONN TECHNOLOGY GROUP |  |  |  |  |  |  |  |  |  |  |  |  |
| BILL OF MATERIAL |  |  |  |  |  |  |  |  |  |  |  |  |
| REV OF  BOM |  | CUSTOMER | <name> |  | CUSTOMER P/N |  | PRODUCT CODE |  | PWA  REV |  | DATE |  |
| Sourcing (Single/Sole/Multi) | Critical Commodity (Y or N) | Component Class (1, 2, other) | Customer PSL (Y or N) | Item Number | Foxconn P/N | Customer P/N | Part Description | Manufacturer  Full Name | Manufacturer  Part Number | Qty | RoHS Status | Location |
